(kicad_pcb
	(version 20260206)
	(generator "pcbnew")
	(generator_version "10.0")
	(general
		(thickness 1.6)
		(legacy_teardrops no)
	)
	(paper "A4")
	(title_block
		(title "v1-chassis-manager — T6M_CM_d_v01_1031_1645.brd")
		(comment 1 "Open CloudServer (Microsoft) / footprints 982-991 of 2512")
	)
	(layers
		(0 "F.Cu" signal "TOP")
		(4 "In1.Cu" signal "GND1")
		(6 "In2.Cu" signal "IN1")
		(8 "In3.Cu" signal "VCC1")
		(10 "In4.Cu" signal "VCC2")
		(12 "In5.Cu" signal "GND2")
		(14 "In6.Cu" signal "IN2")
		(16 "In7.Cu" signal "IN3")
		(18 "In8.Cu" signal "GND3")
		(2 "B.Cu" signal "BOTTOM")
		(9 "F.Adhes" user "F.Adhesive")
		(11 "B.Adhes" user "B.Adhesive")
		(13 "F.Paste" user "Package Geometry/Pastemask Top")
		(15 "B.Paste" user "Package Geometry/Pastemask Bottom")
		(5 "F.SilkS" user "Ref Des/Silkscreen Top")
		(7 "B.SilkS" user "Ref Des/Silkscreen Bottom")
		(1 "F.Mask" user "Board Geometry/Soldermask Top")
		(3 "B.Mask" user "Board Geometry/Soldermask Bottom")
		(17 "Dwgs.User" user "User.Drawings")
		(19 "Cmts.User" user "User.Comments")
		(21 "Eco1.User" user "User.Eco1")
		(23 "Eco2.User" user "User.Eco2")
		(25 "Edge.Cuts" user "Board Geometry/Outline")
		(27 "Margin" user)
		(31 "F.CrtYd" user "Package Geometry/Place Bound Top")
		(29 "B.CrtYd" user "Package Geometry/Place Bound Bottom")
		(35 "F.Fab" user "Ref Des/Assembly Top")
		(33 "B.Fab" user "Ref Des/Assembly Bottom")
	)
	(footprint ""
		(layer "F.Cu")
		(at 152.76576 -185.205624 -90)
		(property "Reference" "R903"
			(at -4.768088 -0.259588 90)
			(unlocked yes)
			(layer "F.SilkS")
			(effects
				(font
					(size 0.7874 0.5842)
					(thickness 0.1524)
				)
				(justify left)
			)
		)
		(property "Value" ""
			(at 0 0 270)
			(layer "F.Fab")
			(effects
				(font
					(size 1.27 1.27)
				)
			)
		)
		(duplicate_pad_numbers_are_jumpers no)
		(fp_line
			(start -0.7874 0.4064)
			(end -0.7874 -0.4064)
			(stroke
				(width 0.1524)
				(type default)
			)
			(layer "F.SilkS")
		)
		(fp_line
			(start 0.7874 0.4064)
			(end -0.7874 0.4064)
			(stroke
				(width 0.1524)
				(type default)
			)
			(layer "F.SilkS")
		)
		(fp_line
			(start -0.7874 -0.4064)
			(end 0.7874 -0.4064)
			(stroke
				(width 0.1524)
				(type default)
			)
			(layer "F.SilkS")
		)
		(fp_line
			(start 0.7874 -0.4064)
			(end 0.7874 0.4064)
			(stroke
				(width 0.1524)
				(type default)
			)
			(layer "F.SilkS")
		)
		(fp_poly
			(pts
				(xy -0.508 0.2794) (xy -0.508 0.2286) (xy -0.635 0.2286) (xy -0.635 -0.254) (xy -0.5334 -0.254)
				(xy -0.5334 -0.2794) (xy 0.5334 -0.2794) (xy 0.5334 -0.254) (xy 0.635 -0.254) (xy 0.635 0.254) (xy 0.5334 0.254)
				(xy 0.5334 0.2794)
			)
			(stroke
				(width 0)
				(type default)
			)
			(fill no)
			(layer "F.CrtYd")
		)
		(pad "1" smd rect
			(at 0.40005 0 270)
			(size 0.4572 0.508)
			(layers "F.Cu" "F.Mask" "F.Paste")
			(net "T12_NODE3_EN")
		)
		(pad "2" smd rect
			(at -0.40005 0 270)
			(size 0.4572 0.508)
			(layers "F.Cu" "F.Mask" "F.Paste")
			(net "T12_NODE3_EN_R")
		)
	)
	(footprint ""
		(layer "F.Cu")
		(at 117.650768 -19.049238 180)
		(property "Reference" "C856"
			(at -4.579874 -2.101596 90)
			(unlocked yes)
			(layer "F.SilkS")
			(effects
				(font
					(size 0.7874 0.5842)
					(thickness 0.1524)
				)
				(justify left)
			)
		)
		(property "Value" ""
			(at 0 0 180)
			(layer "F.Fab")
			(effects
				(font
					(size 1.27 1.27)
				)
			)
		)
		(duplicate_pad_numbers_are_jumpers no)
		(fp_line
			(start 0.7874 0.4064)
			(end -0.7874 0.4064)
			(stroke
				(width 0.1524)
				(type default)
			)
			(layer "F.SilkS")
		)
		(fp_line
			(start 0.7874 -0.4064)
			(end 0.7874 0.4064)
			(stroke
				(width 0.1524)
				(type default)
			)
			(layer "F.SilkS")
		)
		(fp_line
			(start 0 0.381)
			(end 0 -0.381)
			(stroke
				(width 0.1524)
				(type default)
			)
			(layer "F.SilkS")
		)
		(fp_line
			(start -0.7874 0.4064)
			(end -0.7874 -0.4064)
			(stroke
				(width 0.1524)
				(type default)
			)
			(layer "F.SilkS")
		)
		(fp_line
			(start -0.7874 -0.4064)
			(end 0.7874 -0.4064)
			(stroke
				(width 0.1524)
				(type default)
			)
			(layer "F.SilkS")
		)
		(fp_poly
			(pts
				(xy -0.5334 0.254) (xy -0.635 0.254) (xy -0.635 0.2286) (xy -0.635 -0.254) (xy -0.5334 -0.254) (xy -0.5334 -0.2794)
				(xy 0.5334 -0.2794) (xy 0.5334 -0.254) (xy 0.635 -0.254) (xy 0.635 0.254) (xy 0.5334 0.254) (xy 0.5334 0.2794)
				(xy -0.508 0.2794) (xy -0.5334 0.2794)
			)
			(stroke
				(width 0)
				(type default)
			)
			(fill no)
			(layer "F.CrtYd")
		)
		(pad "1" smd rect
			(at 0.40005 0 180)
			(size 0.4572 0.508)
			(layers "F.Cu" "F.Mask" "F.Paste")
			(net "P3V3_STB_NODE1")
		)
		(pad "2" smd rect
			(at -0.40005 0 180)
			(size 0.4572 0.508)
			(layers "F.Cu" "F.Mask" "F.Paste")
			(net "GND")
		)
	)
	(footprint ""
		(layer "F.Cu")
		(at 188.372242 -114.511328 -90)
		(property "Reference" "U101"
			(at -2.175002 -1.619758 0)
			(unlocked yes)
			(layer "F.SilkS")
			(effects
				(font
					(size 0.7874 0.5842)
					(thickness 0.1524)
				)
			)
		)
		(property "Value" ""
			(at 0 0 270)
			(layer "F.Fab")
			(effects
				(font
					(size 1.27 1.27)
				)
			)
		)
		(duplicate_pad_numbers_are_jumpers no)
		(fp_line
			(start -1.651 1.905)
			(end -1.651 -1.905)
			(stroke
				(width 0.1524)
				(type default)
			)
			(layer "F.SilkS")
		)
		(fp_line
			(start 1.651 1.905)
			(end -1.651 1.905)
			(stroke
				(width 0.1524)
				(type default)
			)
			(layer "F.SilkS")
		)
		(fp_line
			(start -1.651 -1.905)
			(end 1.651 -1.905)
			(stroke
				(width 0.1524)
				(type default)
			)
			(layer "F.SilkS")
		)
		(fp_line
			(start 1.651 -1.905)
			(end 1.651 1.905)
			(stroke
				(width 0.1524)
				(type default)
			)
			(layer "F.SilkS")
		)
		(fp_poly
			(pts
				(xy -1.524 0.7112) (xy -1.524 1.7526) (xy -0.508 1.7526) (xy -0.508 0.6985) (xy 0.508 0.6985) (xy 0.508 1.7526)
				(xy 1.524 1.7526) (xy 1.524 0.6985) (xy 1.524 -0.6985) (xy 0.508 -0.6985) (xy 0.508 -1.7526) (xy -0.508 -1.7526)
				(xy -0.508 -0.6985) (xy -1.524 -0.6985) (xy -1.524 0.6985)
			)
			(stroke
				(width 0)
				(type default)
			)
			(fill no)
			(layer "F.CrtYd")
		)
		(fp_text user "1"
			(at -2.312924 0.545592 0)
			(unlocked yes)
			(layer "F.SilkS")
			(effects
				(font
					(size 0.635 0.4064)
					(thickness 0.1524)
				)
			)
		)
		(fp_text user "2"
			(at 2.17678 0.499618 0)
			(unlocked yes)
			(layer "F.SilkS")
			(effects
				(font
					(size 0.635 0.4064)
					(thickness 0.1524)
				)
			)
		)
		(fp_text user "3"
			(at 2.052066 -1.057402 90)
			(unlocked yes)
			(layer "F.SilkS")
			(effects
				(font
					(size 0.635 0.4064)
					(thickness 0.1524)
				)
			)
		)
		(pad "1" smd rect
			(at -1.016 1.1176 270)
			(size 1.016 1.27)
			(layers "F.Cu" "F.Mask" "F.Paste")
			(net "GND")
		)
		(pad "2" smd rect
			(at 1.016 1.1176 270)
			(size 1.016 1.27)
			(layers "F.Cu" "F.Mask" "F.Paste")
			(net "PWRGD_NODE1_P12V_PG_R")
		)
		(pad "3" smd rect
			(at 0 -1.1176 270)
			(size 1.016 1.27)
			(layers "F.Cu" "F.Mask" "F.Paste")
			(net "P12V_NODE1_PWRGD_EN")
		)
	)
	(footprint ""
		(layer "F.Cu")
		(at 48.74514 -163.89985 90)
		(property "Reference" "R537"
			(at -131.03606 -3.625088 90)
			(unlocked yes)
			(layer "F.SilkS")
			(effects
				(font
					(size 0.7874 0.5842)
					(thickness 0.1524)
				)
				(justify left)
			)
		)
		(property "Value" ""
			(at 0 0 90)
			(layer "F.Fab")
			(effects
				(font
					(size 1.27 1.27)
				)
			)
		)
		(duplicate_pad_numbers_are_jumpers no)
		(fp_line
			(start 0.7874 -0.4064)
			(end 0.7874 0.4064)
			(stroke
				(width 0.1524)
				(type default)
			)
			(layer "F.SilkS")
		)
		(fp_line
			(start -0.7874 -0.4064)
			(end 0.7874 -0.4064)
			(stroke
				(width 0.1524)
				(type default)
			)
			(layer "F.SilkS")
		)
		(fp_line
			(start 0.7874 0.4064)
			(end -0.7874 0.4064)
			(stroke
				(width 0.1524)
				(type default)
			)
			(layer "F.SilkS")
		)
		(fp_line
			(start -0.7874 0.4064)
			(end -0.7874 -0.4064)
			(stroke
				(width 0.1524)
				(type default)
			)
			(layer "F.SilkS")
		)
		(fp_poly
			(pts
				(xy -0.508 0.2794) (xy -0.508 0.2286) (xy -0.635 0.2286) (xy -0.635 -0.254) (xy -0.5334 -0.254)
				(xy -0.5334 -0.2794) (xy 0.5334 -0.2794) (xy 0.5334 -0.254) (xy 0.635 -0.254) (xy 0.635 0.254) (xy 0.5334 0.254)
				(xy 0.5334 0.2794)
			)
			(stroke
				(width 0)
				(type default)
			)
			(fill no)
			(layer "F.CrtYd")
		)
		(pad "1" smd rect
			(at 0.40005 0 90)
			(size 0.4572 0.508)
			(layers "F.Cu" "F.Mask" "F.Paste")
			(net "P3V3_NODE1")
		)
		(pad "2" smd rect
			(at -0.40005 0 90)
			(size 0.4572 0.508)
			(layers "F.Cu" "F.Mask" "F.Paste")
			(net "PU_LAN1_TMS")
		)
	)
	(footprint ""
		(layer "F.Cu")
		(at 21.362162 -128.527048 180)
		(property "Reference" "PJ6"
			(at -4.977384 -2.23647 90)
			(unlocked yes)
			(layer "F.SilkS")
			(effects
				(font
					(size 0.7874 0.5842)
					(thickness 0.1524)
				)
				(justify left)
			)
		)
		(property "Value" ""
			(at 0 0 180)
			(layer "F.Fab")
			(effects
				(font
					(size 1.27 1.27)
				)
			)
		)
		(duplicate_pad_numbers_are_jumpers no)
		(fp_poly
			(pts
				(xy 0.2794 0.907796) (xy 0.254 0.907796) (xy 0.254 1.0414) (xy -0.254 1.0414) (xy -0.254 1.034796)
				(xy -0.254 0.933196) (xy -0.2794 0.933196) (xy -0.2794 -0.133604) (xy -0.254 -0.133604) (xy -0.254 -0.235204)
				(xy 0.254 -0.235204) (xy 0.254 -0.133604) (xy 0.2794 -0.133604)
			)
			(stroke
				(width 0)
				(type default)
			)
			(fill no)
			(layer "F.CrtYd")
		)
		(pad "1" smd custom
			(at 0 -0.000254 180)
			(size 0.127 0.127)
			(layers "F.Cu" "F.Mask" "F.Paste")
			(net "FM_CPLD_NODE1_P1V05_EN")
			(options
				(clearance outline)
				(anchor circle)
			)
			(primitives
				(gr_poly
					(pts
						(xy -0.127 0.508) (xy -0.127 -0.0508) (xy -0.254 -0.0508) (xy -0.254 -0.508) (xy 0.254 -0.508)
						(xy 0.254 -0.0508) (xy 0.127 -0.0508) (xy 0.127 0.508)
					)
					(width 0)
					(fill yes)
				)
			)
		)
		(pad "2" smd rect
			(at 0 0.799846 270)
			(size 0.4572 0.508)
			(layers "F.Cu" "F.Mask" "F.Paste")
			(net "P1V05_NODE1_EN")
		)
		(zone
			(layer "F.Cu")
			(hatch none 0.5)
			(connect_pads
				(clearance 0)
			)
			(min_thickness 0.25)
			(keepout
				(tracks allowed)
				(vias not_allowed)
				(pads allowed)
				(copperpour not_allowed)
				(footprints allowed)
			)
			(placement
				(enabled no)
				(sheetname "")
			)
			(fill
				(thermal_gap 0.5)
				(thermal_bridge_width 0.5)
				(island_removal_mode 0)
			)
			(polygon
				(pts
					(xy 21.666962 -129.612644) (xy 21.057362 -129.612644) (xy 21.057362 -128.241044) (xy 21.666962 -128.241044)
				)
			)
		)
	)
	(footprint ""
		(layer "F.Cu")
		(at 81.39176 -188.126624 90)
		(property "Reference" "C661"
			(at 4.548886 -1.831848 90)
			(unlocked yes)
			(layer "F.SilkS")
			(effects
				(font
					(size 0.7874 0.5842)
					(thickness 0.1524)
				)
				(justify left)
			)
		)
		(property "Value" ""
			(at 0 0 90)
			(layer "F.Fab")
			(effects
				(font
					(size 1.27 1.27)
				)
			)
		)
		(duplicate_pad_numbers_are_jumpers no)
		(fp_line
			(start 0.7874 -0.4064)
			(end 0.7874 0.4064)
			(stroke
				(width 0.1524)
				(type default)
			)
			(layer "F.SilkS")
		)
		(fp_line
			(start -0.7874 -0.4064)
			(end 0.7874 -0.4064)
			(stroke
				(width 0.1524)
				(type default)
			)
			(layer "F.SilkS")
		)
		(fp_line
			(start 0 0.381)
			(end 0 -0.381)
			(stroke
				(width 0.1524)
				(type default)
			)
			(layer "F.SilkS")
		)
		(fp_line
			(start 0.7874 0.4064)
			(end -0.7874 0.4064)
			(stroke
				(width 0.1524)
				(type default)
			)
			(layer "F.SilkS")
		)
		(fp_line
			(start -0.7874 0.4064)
			(end -0.7874 -0.4064)
			(stroke
				(width 0.1524)
				(type default)
			)
			(layer "F.SilkS")
		)
		(fp_poly
			(pts
				(xy -0.5334 0.254) (xy -0.635 0.254) (xy -0.635 0.2286) (xy -0.635 -0.254) (xy -0.5334 -0.254) (xy -0.5334 -0.2794)
				(xy 0.5334 -0.2794) (xy 0.5334 -0.254) (xy 0.635 -0.254) (xy 0.635 0.254) (xy 0.5334 0.254) (xy 0.5334 0.2794)
				(xy -0.508 0.2794) (xy -0.5334 0.2794)
			)
			(stroke
				(width 0)
				(type default)
			)
			(fill no)
			(layer "F.CrtYd")
		)
		(pad "1" smd rect
			(at 0.40005 0 90)
			(size 0.4572 0.508)
			(layers "F.Cu" "F.Mask" "F.Paste")
			(net "T4_NODE2_EN_R")
		)
		(pad "2" smd rect
			(at -0.40005 0 90)
			(size 0.4572 0.508)
			(layers "F.Cu" "F.Mask" "F.Paste")
			(net "GND")
		)
	)
	(footprint ""
		(layer "F.Cu")
		(at 144.764252 -149.20595)
		(property "Reference" "R285"
			(at -0.294386 17.331944 0)
			(unlocked yes)
			(layer "F.SilkS")
			(effects
				(font
					(size 0.7874 0.5842)
					(thickness 0.1524)
				)
				(justify left)
			)
		)
		(property "Value" ""
			(at 0 0 0)
			(layer "F.Fab")
			(effects
				(font
					(size 1.27 1.27)
				)
			)
		)
		(duplicate_pad_numbers_are_jumpers no)
		(fp_line
			(start -0.7874 -0.4064)
			(end 0.7874 -0.4064)
			(stroke
				(width 0.1524)
				(type default)
			)
			(layer "F.SilkS")
		)
		(fp_line
			(start -0.7874 0.4064)
			(end -0.7874 -0.4064)
			(stroke
				(width 0.1524)
				(type default)
			)
			(layer "F.SilkS")
		)
		(fp_line
			(start 0.7874 -0.4064)
			(end 0.7874 0.4064)
			(stroke
				(width 0.1524)
				(type default)
			)
			(layer "F.SilkS")
		)
		(fp_line
			(start 0.7874 0.4064)
			(end -0.7874 0.4064)
			(stroke
				(width 0.1524)
				(type default)
			)
			(layer "F.SilkS")
		)
		(fp_poly
			(pts
				(xy -0.508 0.2794) (xy -0.508 0.2286) (xy -0.635 0.2286) (xy -0.635 -0.254) (xy -0.5334 -0.254)
				(xy -0.5334 -0.2794) (xy 0.5334 -0.2794) (xy 0.5334 -0.254) (xy 0.635 -0.254) (xy 0.635 0.254) (xy 0.5334 0.254)
				(xy 0.5334 0.2794)
			)
			(stroke
				(width 0)
				(type default)
			)
			(fill no)
			(layer "F.CrtYd")
		)
		(pad "1" smd rect
			(at 0.40005 0)
			(size 0.4572 0.508)
			(layers "F.Cu" "F.Mask" "F.Paste")
			(net "GND")
		)
		(pad "2" smd rect
			(at -0.40005 0)
			(size 0.4572 0.508)
			(layers "F.Cu" "F.Mask" "F.Paste")
			(net "PCIE_SW_TEST1")
		)
	)
	(footprint ""
		(layer "F.Cu")
		(at 84.171282 -6.73862 180)
		(property "Reference" "PC48"
			(at -2.299462 -3.661156 0)
			(unlocked yes)
			(layer "F.SilkS")
			(effects
				(font
					(size 0.7874 0.5842)
					(thickness 0.1524)
				)
				(justify left)
			)
		)
		(property "Value" ""
			(at 0 0 180)
			(layer "F.Fab")
			(effects
				(font
					(size 1.27 1.27)
				)
			)
		)
		(duplicate_pad_numbers_are_jumpers no)
		(fp_line
			(start 1.905 0.8636)
			(end -1.905 0.8636)
			(stroke
				(width 0.1524)
				(type default)
			)
			(layer "F.SilkS")
		)
		(fp_line
			(start 1.905 -0.8636)
			(end 1.905 0.8636)
			(stroke
				(width 0.1524)
				(type default)
			)
			(layer "F.SilkS")
		)
		(fp_line
			(start 0 0.8382)
			(end 0 -0.8382)
			(stroke
				(width 0.1524)
				(type default)
			)
			(layer "F.SilkS")
		)
		(fp_line
			(start -1.905 0.8636)
			(end -1.905 -0.8636)
			(stroke
				(width 0.1524)
				(type default)
			)
			(layer "F.SilkS")
		)
		(fp_line
			(start -1.905 -0.8636)
			(end 1.905 -0.8636)
			(stroke
				(width 0.1524)
				(type default)
			)
			(layer "F.SilkS")
		)
		(fp_rect
			(start -1.524 0.7366)
			(end 1.524 -0.7366)
			(stroke
				(width 0)
				(type default)
			)
			(fill no)
			(layer "F.CrtYd")
		)
		(pad "1" smd rect
			(at 0.94996 0 180)
			(size 1.1176 1.3716)
			(layers "F.Cu" "F.Mask" "F.Paste")
			(net "P3V3_NODE1")
		)
		(pad "2" smd rect
			(at -0.94996 0 180)
			(size 1.1176 1.3716)
			(layers "F.Cu" "F.Mask" "F.Paste")
			(net "GND")
		)
	)
	(footprint ""
		(layer "F.Cu")
		(at 59.67476 -188.126624 -90)
		(property "Reference" "R943"
			(at -4.548886 -0.297942 90)
			(unlocked yes)
			(layer "F.SilkS")
			(effects
				(font
					(size 0.7874 0.5842)
					(thickness 0.1524)
				)
				(justify left)
			)
		)
		(property "Value" ""
			(at 0 0 270)
			(layer "F.Fab")
			(effects
				(font
					(size 1.27 1.27)
				)
			)
		)
		(duplicate_pad_numbers_are_jumpers no)
		(fp_line
			(start -0.7874 0.4064)
			(end -0.7874 -0.4064)
			(stroke
				(width 0.1524)
				(type default)
			)
			(layer "F.SilkS")
		)
		(fp_line
			(start 0.7874 0.4064)
			(end -0.7874 0.4064)
			(stroke
				(width 0.1524)
				(type default)
			)
			(layer "F.SilkS")
		)
		(fp_line
			(start -0.7874 -0.4064)
			(end 0.7874 -0.4064)
			(stroke
				(width 0.1524)
				(type default)
			)
			(layer "F.SilkS")
		)
		(fp_line
			(start 0.7874 -0.4064)
			(end 0.7874 0.4064)
			(stroke
				(width 0.1524)
				(type default)
			)
			(layer "F.SilkS")
		)
		(fp_poly
			(pts
				(xy -0.508 0.2794) (xy -0.508 0.2286) (xy -0.635 0.2286) (xy -0.635 -0.254) (xy -0.5334 -0.254)
				(xy -0.5334 -0.2794) (xy 0.5334 -0.2794) (xy 0.5334 -0.254) (xy 0.635 -0.254) (xy 0.635 0.254) (xy 0.5334 0.254)
				(xy 0.5334 0.2794)
			)
			(stroke
				(width 0)
				(type default)
			)
			(fill no)
			(layer "F.CrtYd")
		)
		(pad "1" smd rect
			(at 0.40005 0 270)
			(size 0.4572 0.508)
			(layers "F.Cu" "F.Mask" "F.Paste")
			(net "UART_T2_NODE3_RXD")
		)
		(pad "2" smd rect
			(at -0.40005 0 270)
			(size 0.4572 0.508)
			(layers "F.Cu" "F.Mask" "F.Paste")
			(net "UART_T2_NODE3_RXD_R")
		)
	)
	(footprint ""
		(layer "F.Cu")
		(at 79.963518 -88.995504)
		(property "Reference" "R49"
			(at -1.195578 18.989294 0)
			(unlocked yes)
			(layer "F.SilkS")
			(effects
				(font
					(size 0.7874 0.5842)
					(thickness 0.1524)
				)
				(justify left)
			)
		)
		(property "Value" ""
			(at 0 0 0)
			(layer "F.Fab")
			(effects
				(font
					(size 1.27 1.27)
				)
			)
		)
		(duplicate_pad_numbers_are_jumpers no)
		(fp_line
			(start -0.7874 -0.4064)
			(end 0.7874 -0.4064)
			(stroke
				(width 0.1524)
				(type default)
			)
			(layer "F.SilkS")
		)
		(fp_line
			(start -0.7874 0.4064)
			(end -0.7874 -0.4064)
			(stroke
				(width 0.1524)
				(type default)
			)
			(layer "F.SilkS")
		)
		(fp_line
			(start 0.7874 -0.4064)
			(end 0.7874 0.4064)
			(stroke
				(width 0.1524)
				(type default)
			)
			(layer "F.SilkS")
		)
		(fp_line
			(start 0.7874 0.4064)
			(end -0.7874 0.4064)
			(stroke
				(width 0.1524)
				(type default)
			)
			(layer "F.SilkS")
		)
		(fp_poly
			(pts
				(xy -0.508 0.2794) (xy -0.508 0.2286) (xy -0.635 0.2286) (xy -0.635 -0.254) (xy -0.5334 -0.254)
				(xy -0.5334 -0.2794) (xy 0.5334 -0.2794) (xy 0.5334 -0.254) (xy 0.635 -0.254) (xy 0.635 0.254) (xy 0.5334 0.254)
				(xy 0.5334 0.2794)
			)
			(stroke
				(width 0)
				(type default)
			)
			(fill no)
			(layer "F.CrtYd")
		)
		(pad "1" smd rect
			(at 0.40005 0)
			(size 0.4572 0.508)
			(layers "F.Cu" "F.Mask" "F.Paste")
			(net "SPI_CPU_NODE1_WP_L")
		)
		(pad "2" smd rect
			(at -0.40005 0)
			(size 0.4572 0.508)
			(layers "F.Cu" "F.Mask" "F.Paste")
			(net "SPI_CPU_NODE1_WP_R_L")
		)
	)
)
